(kicad_pcb
	(version 20260206)
	(generator "pcbnew")
	(generator_version "10.0")
	(general
		(thickness 1.6)
		(legacy_teardrops no)
	)
	(paper "A4")
	(title_block
		(title "01162023_DA0F0TEBIF0_F0T_Expander_BD_F_brd_V02_OCP.brd")
		(comment 1 "Grand Teton / footprints 4470-4476 of 9728")
	)
	(layers
		(0 "F.Cu" signal "TOP")
		(4 "In1.Cu" signal "GND")
		(6 "In2.Cu" signal "VCC")
		(8 "In3.Cu" signal "VCC1")
		(10 "In4.Cu" signal "GND1")
		(12 "In5.Cu" signal "IN1")
		(14 "In6.Cu" signal "GND2")
		(16 "In7.Cu" signal "IN2")
		(18 "In8.Cu" signal "GND3")
		(20 "In9.Cu" signal "IN3")
		(22 "In10.Cu" signal "GND4")
		(24 "In11.Cu" signal "IN4")
		(26 "In12.Cu" signal "GND5")
		(28 "In13.Cu" signal "IN5")
		(30 "In14.Cu" signal "GND6")
		(32 "In15.Cu" signal "IN6")
		(34 "In16.Cu" signal "GND7")
		(2 "B.Cu" signal "BOTTOM")
		(9 "F.Adhes" user "F.Adhesive")
		(11 "B.Adhes" user "B.Adhesive")
		(13 "F.Paste" user "Package Geometry/Pastemask Top")
		(15 "B.Paste" user "Package Geometry/Pastemask Bottom")
		(5 "F.SilkS" user "Ref Des/Silkscreen Top")
		(7 "B.SilkS" user "Ref Des/Silkscreen Bottom")
		(1 "F.Mask" user "Board Geometry/Soldermask Top")
		(3 "B.Mask" user "Board Geometry/Soldermask Bottom")
		(17 "Dwgs.User" user "User.Drawings")
		(19 "Cmts.User" user "User.Comments")
		(21 "Eco1.User" user "User.Eco1")
		(23 "Eco2.User" user "User.Eco2")
		(25 "Edge.Cuts" user "Board Geometry/Outline")
		(27 "Margin" user)
		(31 "F.CrtYd" user "Package Geometry/Place Bound Top")
		(29 "B.CrtYd" user "Package Geometry/Place Bound Bottom")
		(35 "F.Fab" user "Ref Des/Assembly Top")
		(33 "B.Fab" user "Ref Des/Assembly Bottom")
	)
	(footprint ""
		(layer "F.Cu")
		(at 133.940042 -70.52437 90)
		(property "Reference" "PC841"
			(at 0 0 90)
			(layer "F.SilkS")
			(hide yes)
			(effects
				(font
					(size 1.27 1.27)
				)
			)
		)
		(property "Value" ""
			(at 0 0 90)
			(layer "F.Fab")
			(effects
				(font
					(size 1.27 1.27)
				)
			)
		)
		(duplicate_pad_numbers_are_jumpers no)
		(fp_line
			(start 1.524 -0.762)
			(end 1.524 0.762)
			(stroke
				(width 0.1524)
				(type default)
			)
			(layer "F.SilkS")
		)
		(fp_line
			(start -1.524 -0.762)
			(end 1.524 -0.762)
			(stroke
				(width 0.1524)
				(type default)
			)
			(layer "F.SilkS")
		)
		(fp_line
			(start 1.524 0.762)
			(end -1.524 0.762)
			(stroke
				(width 0.1524)
				(type default)
			)
			(layer "F.SilkS")
		)
		(fp_line
			(start -1.524 0.762)
			(end -1.524 -0.762)
			(stroke
				(width 0.1524)
				(type default)
			)
			(layer "F.SilkS")
		)
		(fp_line
			(start 1.1049 -0.724916)
			(end -1.1049 -0.724916)
			(stroke
				(width 0.1)
				(type default)
			)
			(layer "F.Fab")
		)
		(fp_line
			(start -1.1049 -0.724916)
			(end -1.1049 0.724916)
			(stroke
				(width 0.1)
				(type default)
			)
			(layer "F.Fab")
		)
		(fp_line
			(start 1.1049 0.724916)
			(end 1.1049 -0.724916)
			(stroke
				(width 0.1)
				(type default)
			)
			(layer "F.Fab")
		)
		(fp_line
			(start -1.1049 0.724916)
			(end 1.1049 0.724916)
			(stroke
				(width 0.1)
				(type default)
			)
			(layer "F.Fab")
		)
		(pad "1" smd rect
			(at -0.889 0 270)
			(size 1.016 1.27)
			(layers "F.Cu" "F.Mask" "F.Paste")
			(net "P12V_SSD4_R")
		)
		(pad "2" smd rect
			(at 0.889 0 270)
			(size 1.016 1.27)
			(layers "F.Cu" "F.Mask" "F.Paste")
			(net "GND")
		)
	)
	(footprint ""
		(layer "F.Cu")
		(at 358.405684 -282.421584 -90)
		(property "Reference" "PC178"
			(at 0 0 270)
			(layer "F.SilkS")
			(hide yes)
			(effects
				(font
					(size 1.27 1.27)
				)
			)
		)
		(property "Value" ""
			(at 0 0 270)
			(layer "F.Fab")
			(effects
				(font
					(size 1.27 1.27)
				)
			)
		)
		(duplicate_pad_numbers_are_jumpers no)
		(fp_line
			(start -0.7874 0.4064)
			(end -0.7874 -0.4064)
			(stroke
				(width 0.1524)
				(type default)
			)
			(layer "F.SilkS")
		)
		(fp_line
			(start 0.7874 0.4064)
			(end -0.7874 0.4064)
			(stroke
				(width 0.1524)
				(type default)
			)
			(layer "F.SilkS")
		)
		(fp_line
			(start -0.7874 -0.4064)
			(end 0.7874 -0.4064)
			(stroke
				(width 0.1524)
				(type default)
			)
			(layer "F.SilkS")
		)
		(fp_line
			(start 0.7874 -0.4064)
			(end 0.7874 0.4064)
			(stroke
				(width 0.1524)
				(type default)
			)
			(layer "F.SilkS")
		)
		(fp_line
			(start -0.67945 0.3048)
			(end -0.67945 -0.305054)
			(stroke
				(width 0.1)
				(type default)
			)
			(layer "F.Fab")
		)
		(fp_line
			(start -0.12065 0.3048)
			(end -0.67945 0.3048)
			(stroke
				(width 0.1)
				(type default)
			)
			(layer "F.Fab")
		)
		(fp_line
			(start 0.120396 0.3048)
			(end 0.120396 0.2794)
			(stroke
				(width 0.1)
				(type default)
			)
			(layer "F.Fab")
		)
		(fp_line
			(start 0.67945 0.3048)
			(end 0.120396 0.3048)
			(stroke
				(width 0.1)
				(type default)
			)
			(layer "F.Fab")
		)
		(fp_line
			(start -0.12065 0.2794)
			(end -0.12065 0.3048)
			(stroke
				(width 0.1)
				(type default)
			)
			(layer "F.Fab")
		)
		(fp_line
			(start 0.120396 0.2794)
			(end -0.12065 0.2794)
			(stroke
				(width 0.1)
				(type default)
			)
			(layer "F.Fab")
		)
		(fp_line
			(start -0.12065 -0.2794)
			(end 0.12065 -0.2794)
			(stroke
				(width 0.1)
				(type default)
			)
			(layer "F.Fab")
		)
		(fp_line
			(start 0.12065 -0.2794)
			(end 0.12065 -0.3048)
			(stroke
				(width 0.1)
				(type default)
			)
			(layer "F.Fab")
		)
		(fp_line
			(start 0.12065 -0.3048)
			(end 0.67945 -0.3048)
			(stroke
				(width 0.1)
				(type default)
			)
			(layer "F.Fab")
		)
		(fp_line
			(start 0.67945 -0.3048)
			(end 0.67945 0.3048)
			(stroke
				(width 0.1)
				(type default)
			)
			(layer "F.Fab")
		)
		(fp_line
			(start -0.67945 -0.305054)
			(end -0.12065 -0.305054)
			(stroke
				(width 0.1)
				(type default)
			)
			(layer "F.Fab")
		)
		(fp_line
			(start -0.12065 -0.305054)
			(end -0.12065 -0.2794)
			(stroke
				(width 0.1)
				(type default)
			)
			(layer "F.Fab")
		)
		(pad "1" smd circle
			(at -0.40005 0 270)
			(size 0 0)
			(layers "F.Cu" "F.Mask" "F.Paste")
			(net "P0V8_PEX3_VCC1")
		)
		(pad "2" smd circle
			(at 0.40005 0 270)
			(size 0 0)
			(layers "F.Cu" "F.Mask" "F.Paste")
			(net "GND")
		)
	)
	(footprint ""
		(layer "F.Cu")
		(at 232.823512 -234.728004 -90)
		(property "Reference" "R6192"
			(at 0 0 270)
			(layer "F.SilkS")
			(hide yes)
			(effects
				(font
					(size 1.27 1.27)
				)
			)
		)
		(property "Value" ""
			(at 0 0 270)
			(layer "F.Fab")
			(effects
				(font
					(size 1.27 1.27)
				)
			)
		)
		(duplicate_pad_numbers_are_jumpers no)
		(fp_line
			(start -0.7874 0.4064)
			(end -0.7874 -0.4064)
			(stroke
				(width 0.1524)
				(type default)
			)
			(layer "F.SilkS")
		)
		(fp_line
			(start 0.7874 0.4064)
			(end -0.7874 0.4064)
			(stroke
				(width 0.1524)
				(type default)
			)
			(layer "F.SilkS")
		)
		(fp_line
			(start -0.7874 -0.4064)
			(end 0.7874 -0.4064)
			(stroke
				(width 0.1524)
				(type default)
			)
			(layer "F.SilkS")
		)
		(fp_line
			(start 0.7874 -0.4064)
			(end 0.7874 0.4064)
			(stroke
				(width 0.1524)
				(type default)
			)
			(layer "F.SilkS")
		)
		(fp_line
			(start -0.67945 0.3048)
			(end -0.67945 -0.305054)
			(stroke
				(width 0.1)
				(type default)
			)
			(layer "F.Fab")
		)
		(fp_line
			(start -0.12065 0.3048)
			(end -0.67945 0.3048)
			(stroke
				(width 0.1)
				(type default)
			)
			(layer "F.Fab")
		)
		(fp_line
			(start 0.120396 0.3048)
			(end 0.120396 0.2794)
			(stroke
				(width 0.1)
				(type default)
			)
			(layer "F.Fab")
		)
		(fp_line
			(start 0.67945 0.3048)
			(end 0.120396 0.3048)
			(stroke
				(width 0.1)
				(type default)
			)
			(layer "F.Fab")
		)
		(fp_line
			(start -0.12065 0.2794)
			(end -0.12065 0.3048)
			(stroke
				(width 0.1)
				(type default)
			)
			(layer "F.Fab")
		)
		(fp_line
			(start 0.120396 0.2794)
			(end -0.12065 0.2794)
			(stroke
				(width 0.1)
				(type default)
			)
			(layer "F.Fab")
		)
		(fp_line
			(start -0.12065 -0.2794)
			(end 0.12065 -0.2794)
			(stroke
				(width 0.1)
				(type default)
			)
			(layer "F.Fab")
		)
		(fp_line
			(start 0.12065 -0.2794)
			(end 0.12065 -0.3048)
			(stroke
				(width 0.1)
				(type default)
			)
			(layer "F.Fab")
		)
		(fp_line
			(start 0.12065 -0.3048)
			(end 0.67945 -0.3048)
			(stroke
				(width 0.1)
				(type default)
			)
			(layer "F.Fab")
		)
		(fp_line
			(start 0.67945 -0.3048)
			(end 0.67945 0.3048)
			(stroke
				(width 0.1)
				(type default)
			)
			(layer "F.Fab")
		)
		(fp_line
			(start -0.67945 -0.305054)
			(end -0.12065 -0.305054)
			(stroke
				(width 0.1)
				(type default)
			)
			(layer "F.Fab")
		)
		(fp_line
			(start -0.12065 -0.305054)
			(end -0.12065 -0.2794)
			(stroke
				(width 0.1)
				(type default)
			)
			(layer "F.Fab")
		)
		(pad "1" smd circle
			(at -0.40005 0 270)
			(size 0 0)
			(layers "F.Cu" "F.Mask" "F.Paste")
			(net "GND")
		)
		(pad "2" smd circle
			(at 0.40005 0 270)
			(size 0 0)
			(layers "F.Cu" "F.Mask" "F.Paste")
			(net "SSD10_PWRDIS_BIC_R")
		)
	)
	(footprint ""
		(layer "F.Cu")
		(at 369.08359 -6.703822)
		(property "Reference" "R5819"
			(at 0 0 0)
			(layer "F.SilkS")
			(hide yes)
			(effects
				(font
					(size 1.27 1.27)
				)
			)
		)
		(property "Value" ""
			(at 0 0 0)
			(layer "F.Fab")
			(effects
				(font
					(size 1.27 1.27)
				)
			)
		)
		(duplicate_pad_numbers_are_jumpers no)
		(fp_line
			(start -0.7874 -0.4064)
			(end 0.7874 -0.4064)
			(stroke
				(width 0.1524)
				(type default)
			)
			(layer "F.SilkS")
		)
		(fp_line
			(start -0.7874 0.4064)
			(end -0.7874 -0.4064)
			(stroke
				(width 0.1524)
				(type default)
			)
			(layer "F.SilkS")
		)
		(fp_line
			(start 0.7874 -0.4064)
			(end 0.7874 0.4064)
			(stroke
				(width 0.1524)
				(type default)
			)
			(layer "F.SilkS")
		)
		(fp_line
			(start 0.7874 0.4064)
			(end -0.7874 0.4064)
			(stroke
				(width 0.1524)
				(type default)
			)
			(layer "F.SilkS")
		)
		(fp_line
			(start -0.67945 -0.305054)
			(end -0.12065 -0.305054)
			(stroke
				(width 0.1)
				(type default)
			)
			(layer "F.Fab")
		)
		(fp_line
			(start -0.67945 0.3048)
			(end -0.67945 -0.305054)
			(stroke
				(width 0.1)
				(type default)
			)
			(layer "F.Fab")
		)
		(fp_line
			(start -0.12065 -0.305054)
			(end -0.12065 -0.2794)
			(stroke
				(width 0.1)
				(type default)
			)
			(layer "F.Fab")
		)
		(fp_line
			(start -0.12065 -0.2794)
			(end 0.12065 -0.2794)
			(stroke
				(width 0.1)
				(type default)
			)
			(layer "F.Fab")
		)
		(fp_line
			(start -0.12065 0.2794)
			(end -0.12065 0.3048)
			(stroke
				(width 0.1)
				(type default)
			)
			(layer "F.Fab")
		)
		(fp_line
			(start -0.12065 0.3048)
			(end -0.67945 0.3048)
			(stroke
				(width 0.1)
				(type default)
			)
			(layer "F.Fab")
		)
		(fp_line
			(start 0.120396 0.2794)
			(end -0.12065 0.2794)
			(stroke
				(width 0.1)
				(type default)
			)
			(layer "F.Fab")
		)
		(fp_line
			(start 0.120396 0.3048)
			(end 0.120396 0.2794)
			(stroke
				(width 0.1)
				(type default)
			)
			(layer "F.Fab")
		)
		(fp_line
			(start 0.12065 -0.3048)
			(end 0.67945 -0.3048)
			(stroke
				(width 0.1)
				(type default)
			)
			(layer "F.Fab")
		)
		(fp_line
			(start 0.12065 -0.2794)
			(end 0.12065 -0.3048)
			(stroke
				(width 0.1)
				(type default)
			)
			(layer "F.Fab")
		)
		(fp_line
			(start 0.67945 -0.3048)
			(end 0.67945 0.3048)
			(stroke
				(width 0.1)
				(type default)
			)
			(layer "F.Fab")
		)
		(fp_line
			(start 0.67945 0.3048)
			(end 0.120396 0.3048)
			(stroke
				(width 0.1)
				(type default)
			)
			(layer "F.Fab")
		)
		(pad "1" smd circle
			(at -0.40005 0)
			(size 0 0)
			(layers "F.Cu" "F.Mask" "F.Paste")
			(net "SMB_BIC_I2C6_MUX_THERMAL_R2_SCL")
		)
		(pad "2" smd circle
			(at 0.40005 0)
			(size 0 0)
			(layers "F.Cu" "F.Mask" "F.Paste")
			(net "SMB_LM75_3_SCL")
		)
	)
	(footprint ""
		(layer "F.Cu")
		(at 238.992664 -203.59116 180)
		(property "Reference" "OSC2"
			(at -1.422146 1.070102 0)
			(unlocked yes)
			(layer "F.SilkS")
			(effects
				(font
					(size 0.7874 0.5842)
					(thickness 0.1524)
				)
				(justify left)
			)
		)
		(property "Value" ""
			(at 0 0 180)
			(layer "F.Fab")
			(effects
				(font
					(size 1.27 1.27)
				)
			)
		)
		(duplicate_pad_numbers_are_jumpers no)
		(fp_line
			(start 1.299972 1.599946)
			(end -1.299972 1.599946)
			(stroke
				(width 0.1524)
				(type default)
			)
			(layer "F.SilkS")
		)
		(fp_line
			(start 1.299972 -1.599946)
			(end 1.299972 1.599946)
			(stroke
				(width 0.1524)
				(type default)
			)
			(layer "F.SilkS")
		)
		(fp_line
			(start -1.299972 1.599946)
			(end -1.299972 -1.599946)
			(stroke
				(width 0.1524)
				(type default)
			)
			(layer "F.SilkS")
		)
		(fp_line
			(start -1.299972 -1.599946)
			(end 1.299972 -1.599946)
			(stroke
				(width 0.1524)
				(type default)
			)
			(layer "F.SilkS")
		)
		(fp_poly
			(pts
				(xy -1.815592 0.656082) (xy -2.533904 -0.062484) (xy -1.456436 -0.42164)
			)
			(stroke
				(width 0)
				(type default)
			)
			(fill yes)
			(layer "F.SilkS")
		)
		(fp_line
			(start 1.050036 1.299972)
			(end -1.050036 1.299972)
			(stroke
				(width 0.1)
				(type default)
			)
			(layer "F.Fab")
		)
		(fp_line
			(start 1.050036 -1.299972)
			(end 1.050036 1.299972)
			(stroke
				(width 0.1)
				(type default)
			)
			(layer "F.Fab")
		)
		(fp_line
			(start -1.050036 1.299972)
			(end -1.050036 -1.299972)
			(stroke
				(width 0.1)
				(type default)
			)
			(layer "F.Fab")
		)
		(fp_line
			(start -1.050036 -1.299972)
			(end 1.050036 -1.299972)
			(stroke
				(width 0.1)
				(type default)
			)
			(layer "F.Fab")
		)
		(fp_poly
			(pts
				(xy -2.4892 -0.24892) (xy -2.4892 -1.26492) (xy -1.4732 -0.75692)
			)
			(stroke
				(width 0)
				(type default)
			)
			(fill yes)
			(layer "F.Fab")
		)
		(pad "1" smd rect
			(at -0.649986 -0.849884 180)
			(size 1.016 1.2192)
			(layers "F.Cu" "F.Mask" "F.Paste")
			(net "PU_CLK_25M_BIC_EN")
		)
		(pad "2" smd rect
			(at -0.649986 0.849884 180)
			(size 1.016 1.2192)
			(layers "F.Cu" "F.Mask" "F.Paste")
			(net "GND")
		)
		(pad "3" smd rect
			(at 0.649986 0.849884 180)
			(size 1.016 1.2192)
			(layers "F.Cu" "F.Mask" "F.Paste")
			(net "CLK_25M_BIC")
		)
		(pad "4" smd rect
			(at 0.649986 -0.849884 180)
			(size 1.016 1.2192)
			(layers "F.Cu" "F.Mask" "F.Paste")
			(net "P3V3_AUX")
		)
	)
	(footprint ""
		(layer "F.Cu")
		(at 143.432276 -32.848042 90)
		(property "Reference" "PC927"
			(at 0 0 90)
			(layer "F.SilkS")
			(hide yes)
			(effects
				(font
					(size 1.27 1.27)
				)
			)
		)
		(property "Value" ""
			(at 0 0 90)
			(layer "F.Fab")
			(effects
				(font
					(size 1.27 1.27)
				)
			)
		)
		(duplicate_pad_numbers_are_jumpers no)
		(fp_line
			(start 0.7874 -0.4064)
			(end 0.7874 0.4064)
			(stroke
				(width 0.1524)
				(type default)
			)
			(layer "F.SilkS")
		)
		(fp_line
			(start -0.7874 -0.4064)
			(end 0.7874 -0.4064)
			(stroke
				(width 0.1524)
				(type default)
			)
			(layer "F.SilkS")
		)
		(fp_line
			(start 0.7874 0.4064)
			(end -0.7874 0.4064)
			(stroke
				(width 0.1524)
				(type default)
			)
			(layer "F.SilkS")
		)
		(fp_line
			(start -0.7874 0.4064)
			(end -0.7874 -0.4064)
			(stroke
				(width 0.1524)
				(type default)
			)
			(layer "F.SilkS")
		)
		(fp_line
			(start -0.12065 -0.305054)
			(end -0.12065 -0.2794)
			(stroke
				(width 0.1)
				(type default)
			)
			(layer "F.Fab")
		)
		(fp_line
			(start -0.67945 -0.305054)
			(end -0.12065 -0.305054)
			(stroke
				(width 0.1)
				(type default)
			)
			(layer "F.Fab")
		)
		(fp_line
			(start 0.67945 -0.3048)
			(end 0.67945 0.3048)
			(stroke
				(width 0.1)
				(type default)
			)
			(layer "F.Fab")
		)
		(fp_line
			(start 0.12065 -0.3048)
			(end 0.67945 -0.3048)
			(stroke
				(width 0.1)
				(type default)
			)
			(layer "F.Fab")
		)
		(fp_line
			(start 0.12065 -0.2794)
			(end 0.12065 -0.3048)
			(stroke
				(width 0.1)
				(type default)
			)
			(layer "F.Fab")
		)
		(fp_line
			(start -0.12065 -0.2794)
			(end 0.12065 -0.2794)
			(stroke
				(width 0.1)
				(type default)
			)
			(layer "F.Fab")
		)
		(fp_line
			(start 0.120396 0.2794)
			(end -0.12065 0.2794)
			(stroke
				(width 0.1)
				(type default)
			)
			(layer "F.Fab")
		)
		(fp_line
			(start -0.12065 0.2794)
			(end -0.12065 0.3048)
			(stroke
				(width 0.1)
				(type default)
			)
			(layer "F.Fab")
		)
		(fp_line
			(start 0.67945 0.3048)
			(end 0.120396 0.3048)
			(stroke
				(width 0.1)
				(type default)
			)
			(layer "F.Fab")
		)
		(fp_line
			(start 0.120396 0.3048)
			(end 0.120396 0.2794)
			(stroke
				(width 0.1)
				(type default)
			)
			(layer "F.Fab")
		)
		(fp_line
			(start -0.12065 0.3048)
			(end -0.67945 0.3048)
			(stroke
				(width 0.1)
				(type default)
			)
			(layer "F.Fab")
		)
		(fp_line
			(start -0.67945 0.3048)
			(end -0.67945 -0.305054)
			(stroke
				(width 0.1)
				(type default)
			)
			(layer "F.Fab")
		)
		(pad "1" smd circle
			(at -0.40005 0 90)
			(size 0 0)
			(layers "F.Cu" "F.Mask" "F.Paste")
			(net "P3V3_SSD5_CO_DV_DT")
		)
		(pad "2" smd circle
			(at 0.40005 0 90)
			(size 0 0)
			(layers "F.Cu" "F.Mask" "F.Paste")
			(net "GND")
		)
	)
	(footprint ""
		(layer "F.Cu")
		(at 160.82264 -44.341542 90)
		(property "Reference" "R569"
			(at 0 0 90)
			(layer "F.SilkS")
			(hide yes)
			(effects
				(font
					(size 1.27 1.27)
				)
			)
		)
		(property "Value" ""
			(at 0 0 90)
			(layer "F.Fab")
			(effects
				(font
					(size 1.27 1.27)
				)
			)
		)
		(duplicate_pad_numbers_are_jumpers no)
		(fp_line
			(start 0.7874 -0.4064)
			(end 0.7874 0.4064)
			(stroke
				(width 0.1524)
				(type default)
			)
			(layer "F.SilkS")
		)
		(fp_line
			(start -0.7874 -0.4064)
			(end 0.7874 -0.4064)
			(stroke
				(width 0.1524)
				(type default)
			)
			(layer "F.SilkS")
		)
		(fp_line
			(start 0.7874 0.4064)
			(end -0.7874 0.4064)
			(stroke
				(width 0.1524)
				(type default)
			)
			(layer "F.SilkS")
		)
		(fp_line
			(start -0.7874 0.4064)
			(end -0.7874 -0.4064)
			(stroke
				(width 0.1524)
				(type default)
			)
			(layer "F.SilkS")
		)
		(fp_line
			(start -0.12065 -0.305054)
			(end -0.12065 -0.2794)
			(stroke
				(width 0.1)
				(type default)
			)
			(layer "F.Fab")
		)
		(fp_line
			(start -0.67945 -0.305054)
			(end -0.12065 -0.305054)
			(stroke
				(width 0.1)
				(type default)
			)
			(layer "F.Fab")
		)
		(fp_line
			(start 0.67945 -0.3048)
			(end 0.67945 0.3048)
			(stroke
				(width 0.1)
				(type default)
			)
			(layer "F.Fab")
		)
		(fp_line
			(start 0.12065 -0.3048)
			(end 0.67945 -0.3048)
			(stroke
				(width 0.1)
				(type default)
			)
			(layer "F.Fab")
		)
		(fp_line
			(start 0.12065 -0.2794)
			(end 0.12065 -0.3048)
			(stroke
				(width 0.1)
				(type default)
			)
			(layer "F.Fab")
		)
		(fp_line
			(start -0.12065 -0.2794)
			(end 0.12065 -0.2794)
			(stroke
				(width 0.1)
				(type default)
			)
			(layer "F.Fab")
		)
		(fp_line
			(start 0.120396 0.2794)
			(end -0.12065 0.2794)
			(stroke
				(width 0.1)
				(type default)
			)
			(layer "F.Fab")
		)
		(fp_line
			(start -0.12065 0.2794)
			(end -0.12065 0.3048)
			(stroke
				(width 0.1)
				(type default)
			)
			(layer "F.Fab")
		)
		(fp_line
			(start 0.67945 0.3048)
			(end 0.120396 0.3048)
			(stroke
				(width 0.1)
				(type default)
			)
			(layer "F.Fab")
		)
		(fp_line
			(start 0.120396 0.3048)
			(end 0.120396 0.2794)
			(stroke
				(width 0.1)
				(type default)
			)
			(layer "F.Fab")
		)
		(fp_line
			(start -0.12065 0.3048)
			(end -0.67945 0.3048)
			(stroke
				(width 0.1)
				(type default)
			)
			(layer "F.Fab")
		)
		(fp_line
			(start -0.67945 0.3048)
			(end -0.67945 -0.305054)
			(stroke
				(width 0.1)
				(type default)
			)
			(layer "F.Fab")
		)
		(pad "1" smd circle
			(at -0.40005 0 90)
			(size 0 0)
			(layers "F.Cu" "F.Mask" "F.Paste")
			(net "P12V_SSD5")
		)
		(pad "2" smd circle
			(at 0.40005 0 90)
			(size 0 0)
			(layers "F.Cu" "F.Mask" "F.Paste")
			(net "P12V_SSD5_VIN_N")
		)
	)
)
